(kicad_pcb
	(version 20221018)
	(generator pcbnew)
	(general
    (thickness 1.62)
  )
	(paper "A4")
	(title_block
    (title "ECP5 - Datacenter Secure Control Module (DC-SCM)")
    (date "2024-07-01")
    (rev "1.2.1")
		(comment 9 "footprints 296-303 of 506")
	)
	(layers
    (0 "F.Cu" signal)
    (1 "In1.Cu" power)
    (2 "In2.Cu" signal)
    (3 "In3.Cu" power)
    (4 "In4.Cu" power)
    (5 "In5.Cu" signal)
    (6 "In6.Cu" power)
    (31 "B.Cu" signal)
    (32 "B.Adhes" user "B.Adhesive")
    (33 "F.Adhes" user "F.Adhesive")
    (34 "B.Paste" user)
    (35 "F.Paste" user)
    (36 "B.SilkS" user "B.Silkscreen")
    (37 "F.SilkS" user "F.Silkscreen")
    (38 "B.Mask" user)
    (39 "F.Mask" user)
    (40 "Dwgs.User" user "User.Drawings")
    (41 "Cmts.User" user "User.Comments")
    (42 "Eco1.User" user "User.Eco1")
    (43 "Eco2.User" user "User.Eco2")
    (44 "Edge.Cuts" user)
    (45 "Margin" user)
    (46 "B.CrtYd" user "B.Courtyard")
    (47 "F.CrtYd" user "F.Courtyard")
    (48 "B.Fab" user)
    (49 "F.Fab" user)
  )
	(footprint "antmicro-footprints:C_0402_1005Metric" (layer "B.Cu")
    (at 106.025 132.25 90)
    (descr "Capacitor SMD 0402")
    (tags "capacitor SMD 0402")
    (property "Author" "Antmicro")
    (property "Dielectric" "X7R")
    (property "License" "Apache-2.0")
    (property "MPN" "GRM155R71H103KA88D")
    (property "Manufacturer" "Murata")
    (property "Public" "False")
    (property "Sheetfile" "fpga-power-supply.kicad_sch")
    (property "Sheetname" "FPGA power supply")
    (property "Val" "10n")
    (property "Voltage" "50V")
    (property "ki_description" "SMD Multilayer Ceramic Capacitor, 10000 pF, 50 V, 0402 [1005 Metric], ± 10%, X7R, GRM Series")
    (property "ki_keywords" "0402, SMT, CAPACITOR, PASSIVE")
    (attr smd)
    (fp_text reference "C175" (at -20.855 0.875 90) (layer "B.SilkS")
        (effects (font (size 0.7 0.7) (thickness 0.127)) (justify mirror))
    )
    (fp_text value "C_10n_0402" (at 0 -1.17 90) (layer "B.Fab")
        (effects (font (size 1 1) (thickness 0.15)) (justify mirror))
    )
    (fp_text user "${REFERENCE}" (at 0 0 90) (layer "B.Fab")
        (effects (font (size 0.25 0.25) (thickness 0.04)) (justify mirror))
    )
    (fp_text user "License: Apache-2.0" (at -0.939 -5.799 270) (layer "B.Fab") hide
        (effects (font (size 0.7 0.7) (thickness 0.15)) (justify left bottom mirror))
    )
    (fp_text user "Author: Antmicro" (at -0.939 -3.399 270) (layer "B.Fab") hide
        (effects (font (size 0.7 0.7) (thickness 0.15)) (justify left bottom mirror))
    )
    (fp_rect (start -0.925 0.47) (end 0.925 -0.47)
      (stroke (width 0.05) (type default)) (fill none) (layer "B.CrtYd"))
    (fp_line (start -0.494 -0.248) (end -0.494 0.25)
      (stroke (width 0.15) (type solid)) (layer "B.Fab"))
    (fp_line (start -0.494 0.25) (end 0.504 0.25)
      (stroke (width 0.15) (type solid)) (layer "B.Fab"))
    (fp_line (start 0.504 -0.248) (end -0.494 -0.248)
      (stroke (width 0.15) (type solid)) (layer "B.Fab"))
    (fp_line (start 0.504 0.25) (end 0.504 -0.248)
      (stroke (width 0.15) (type solid)) (layer "B.Fab"))
    (pad "1" smd roundrect (at -0.48 0 90) (size 0.59 0.64) (layers "B.Cu" "B.Paste" "B.Mask") (roundrect_rratio 0.25)
      (net 1 "GND") (pintype "passive"))
    (pad "2" smd roundrect (at 0.48 0 90) (size 0.59 0.64) (layers "B.Cu" "B.Paste" "B.Mask") (roundrect_rratio 0.25)
      (net 303 "/FPGA power supply/VCCA1") (pintype "passive"))
  )
	(footprint "antmicro-footprints:C_0402_1005Metric" (layer "B.Cu")
    (at 108.715 125.5)
    (descr "Capacitor SMD 0402")
    (tags "capacitor SMD 0402")
    (property "Author" "Antmicro")
    (property "Dielectric" "")
    (property "License" "Apache-2.0")
    (property "MPN" "C1005X5R1E474M050BB")
    (property "Manufacturer" "TDK")
    (property "Public" "False")
    (property "Sheetfile" "fpga-power-supply.kicad_sch")
    (property "Sheetname" "FPGA power supply")
    (property "Val" "470n")
    (property "Voltage" "")
    (property "ki_description" "SMD Multilayer Ceramic Capacitor, 0.47 µF, 25 V, 0402 [1005 Metric], ± 20%, X5R, C")
    (property "ki_keywords" "0402, SMT, CAPACITOR, PASSIVE, CERAMIC, MLCC")
    (attr smd)
    (fp_text reference "C176" (at -0.385 -22.95) (layer "B.SilkS")
        (effects (font (size 0.7 0.7) (thickness 0.127)) (justify mirror))
    )
    (fp_text value "C_470n_0402" (at 0 -1.17) (layer "B.Fab")
        (effects (font (size 1 1) (thickness 0.15)) (justify mirror))
    )
    (fp_text user "${REFERENCE}" (at 0 0) (layer "B.Fab")
        (effects (font (size 0.25 0.25) (thickness 0.04)) (justify mirror))
    )
    (fp_text user "Author: Antmicro" (at -0.939 -3.399 180) (layer "B.Fab") hide
        (effects (font (size 0.7 0.7) (thickness 0.15)) (justify left bottom mirror))
    )
    (fp_text user "License: Apache-2.0" (at -0.939 -5.799 180) (layer "B.Fab") hide
        (effects (font (size 0.7 0.7) (thickness 0.15)) (justify left bottom mirror))
    )
    (fp_rect (start -0.925 0.47) (end 0.925 -0.47)
      (stroke (width 0.05) (type default)) (fill none) (layer "B.CrtYd"))
    (fp_line (start -0.494 -0.248) (end -0.494 0.25)
      (stroke (width 0.15) (type solid)) (layer "B.Fab"))
    (fp_line (start -0.494 0.25) (end 0.504 0.25)
      (stroke (width 0.15) (type solid)) (layer "B.Fab"))
    (fp_line (start 0.504 -0.248) (end -0.494 -0.248)
      (stroke (width 0.15) (type solid)) (layer "B.Fab"))
    (fp_line (start 0.504 0.25) (end 0.504 -0.248)
      (stroke (width 0.15) (type solid)) (layer "B.Fab"))
    (pad "1" smd roundrect (at -0.48 0) (size 0.59 0.64) (layers "B.Cu" "B.Paste" "B.Mask") (roundrect_rratio 0.25)
      (net 1 "GND") (pintype "passive"))
    (pad "2" smd roundrect (at 0.48 0) (size 0.59 0.64) (layers "B.Cu" "B.Paste" "B.Mask") (roundrect_rratio 0.25)
      (net 304 "/FPGA power supply/VCCAUX") (pintype "passive"))
  )
	(footprint "antmicro-footprints:C_0402_1005Metric" (layer "B.Cu")
    (at 108.4 124.05 -90)
    (descr "Capacitor SMD 0402")
    (tags "capacitor SMD 0402")
    (property "Author" "Antmicro")
    (property "Dielectric" "")
    (property "License" "Apache-2.0")
    (property "MPN" "C1005X5R1E474M050BB")
    (property "Manufacturer" "TDK")
    (property "Public" "False")
    (property "Sheetfile" "fpga-power-supply.kicad_sch")
    (property "Sheetname" "FPGA power supply")
    (property "Val" "470n")
    (property "Voltage" "")
    (property "ki_description" "SMD Multilayer Ceramic Capacitor, 0.47 µF, 25 V, 0402 [1005 Metric], ± 20%, X5R, C")
    (property "ki_keywords" "0402, SMT, CAPACITOR, PASSIVE, CERAMIC, MLCC")
    (attr smd)
    (fp_text reference "C177" (at 22.475 -0.16 90) (layer "B.SilkS")
        (effects (font (size 0.7 0.7) (thickness 0.127)) (justify mirror))
    )
    (fp_text value "C_470n_0402" (at 0 -1.17 90) (layer "B.Fab")
        (effects (font (size 1 1) (thickness 0.15)) (justify mirror))
    )
    (fp_text user "Author: Antmicro" (at -0.939 -3.399 90) (layer "B.Fab") hide
        (effects (font (size 0.7 0.7) (thickness 0.15)) (justify left bottom mirror))
    )
    (fp_text user "${REFERENCE}" (at 0 0 90) (layer "B.Fab")
        (effects (font (size 0.25 0.25) (thickness 0.04)) (justify mirror))
    )
    (fp_text user "License: Apache-2.0" (at -0.939 -5.799 90) (layer "B.Fab") hide
        (effects (font (size 0.7 0.7) (thickness 0.15)) (justify left bottom mirror))
    )
    (fp_rect (start -0.925 0.47) (end 0.925 -0.47)
      (stroke (width 0.05) (type default)) (fill none) (layer "B.CrtYd"))
    (fp_line (start -0.494 -0.248) (end -0.494 0.25)
      (stroke (width 0.15) (type solid)) (layer "B.Fab"))
    (fp_line (start -0.494 0.25) (end 0.504 0.25)
      (stroke (width 0.15) (type solid)) (layer "B.Fab"))
    (fp_line (start 0.504 -0.248) (end -0.494 -0.248)
      (stroke (width 0.15) (type solid)) (layer "B.Fab"))
    (fp_line (start 0.504 0.25) (end 0.504 -0.248)
      (stroke (width 0.15) (type solid)) (layer "B.Fab"))
    (pad "1" smd roundrect (at -0.48 0 270) (size 0.59 0.64) (layers "B.Cu" "B.Paste" "B.Mask") (roundrect_rratio 0.25)
      (net 211 "VCC1V2") (pintype "passive"))
    (pad "2" smd roundrect (at 0.48 0 270) (size 0.59 0.64) (layers "B.Cu" "B.Paste" "B.Mask") (roundrect_rratio 0.25)
      (net 1 "GND") (pintype "passive"))
  )
	(footprint "antmicro-footprints:C_0402_1005Metric" (layer "B.Cu")
    (at 104.85 130.2)
    (descr "Capacitor SMD 0402")
    (tags "capacitor SMD 0402")
    (property "Author" "Antmicro")
    (property "Dielectric" "C0G")
    (property "License" "Apache-2.0")
    (property "MPN" "GRM1555C1H102JA01D")
    (property "Manufacturer" "Murata")
    (property "Public" "False")
    (property "Sheetfile" "fpga-power-supply.kicad_sch")
    (property "Sheetname" "FPGA power supply")
    (property "Val" "1n")
    (property "Voltage" "50V")
    (property "ki_description" "SMD Multilayer Ceramic Capacitor, 1000 pF, 50 V, 0402 [1005 Metric], ± 5%, C0G / NP0, GRM Series")
    (property "ki_keywords" "0402, SMT, CAPACITOR, PASSIVE, CERAMIC, MLCC")
    (attr smd)
    (fp_text reference "C178" (at 0.35 20.785) (layer "B.SilkS")
        (effects (font (size 0.7 0.7) (thickness 0.127)) (justify mirror))
    )
    (fp_text value "C_1n_0402" (at 0 -1.17) (layer "B.Fab")
        (effects (font (size 1 1) (thickness 0.15)) (justify mirror))
    )
    (fp_text user "Author: Antmicro" (at -0.939 -3.399 180) (layer "B.Fab") hide
        (effects (font (size 0.7 0.7) (thickness 0.15)) (justify left bottom mirror))
    )
    (fp_text user "License: Apache-2.0" (at -0.939 -5.799 180) (layer "B.Fab") hide
        (effects (font (size 0.7 0.7) (thickness 0.15)) (justify left bottom mirror))
    )
    (fp_text user "${REFERENCE}" (at 0 0) (layer "B.Fab")
        (effects (font (size 0.25 0.25) (thickness 0.04)) (justify mirror))
    )
    (fp_rect (start -0.925 0.47) (end 0.925 -0.47)
      (stroke (width 0.05) (type default)) (fill none) (layer "B.CrtYd"))
    (fp_line (start -0.494 -0.248) (end -0.494 0.25)
      (stroke (width 0.15) (type solid)) (layer "B.Fab"))
    (fp_line (start -0.494 0.25) (end 0.504 0.25)
      (stroke (width 0.15) (type solid)) (layer "B.Fab"))
    (fp_line (start 0.504 -0.248) (end -0.494 -0.248)
      (stroke (width 0.15) (type solid)) (layer "B.Fab"))
    (fp_line (start 0.504 0.25) (end 0.504 -0.248)
      (stroke (width 0.15) (type solid)) (layer "B.Fab"))
    (pad "1" smd roundrect (at -0.48 0) (size 0.59 0.64) (layers "B.Cu" "B.Paste" "B.Mask") (roundrect_rratio 0.25)
      (net 1 "GND") (pintype "passive"))
    (pad "2" smd roundrect (at 0.48 0) (size 0.59 0.64) (layers "B.Cu" "B.Paste" "B.Mask") (roundrect_rratio 0.25)
      (net 303 "/FPGA power supply/VCCA1") (pintype "passive"))
  )
	(footprint "antmicro-footprints:C_0402_1005Metric" (layer "B.Cu")
    (at 99.5 124.95 -90)
    (descr "Capacitor SMD 0402")
    (tags "capacitor SMD 0402")
    (property "Author" "Antmicro")
    (property "Dielectric" "")
    (property "License" "Apache-2.0")
    (property "MPN" "C1005X5R1E474M050BB")
    (property "Manufacturer" "TDK")
    (property "Public" "False")
    (property "Sheetfile" "fpga-power-supply.kicad_sch")
    (property "Sheetname" "FPGA power supply")
    (property "Val" "470n")
    (property "Voltage" "")
    (property "ki_description" "SMD Multilayer Ceramic Capacitor, 0.47 µF, 25 V, 0402 [1005 Metric], ± 20%, X5R, C")
    (property "ki_keywords" "0402, SMT, CAPACITOR, PASSIVE, CERAMIC, MLCC")
    (attr smd)
    (fp_text reference "C179" (at -23 0 90) (layer "B.SilkS")
        (effects (font (size 0.7 0.7) (thickness 0.127)) (justify mirror))
    )
    (fp_text value "C_470n_0402" (at 0 -1.17 90) (layer "B.Fab")
        (effects (font (size 1 1) (thickness 0.15)) (justify mirror))
    )
    (fp_text user "Author: Antmicro" (at -0.939 -3.399 90) (layer "B.Fab") hide
        (effects (font (size 0.7 0.7) (thickness 0.15)) (justify left bottom mirror))
    )
    (fp_text user "${REFERENCE}" (at 0 0 90) (layer "B.Fab")
        (effects (font (size 0.25 0.25) (thickness 0.04)) (justify mirror))
    )
    (fp_text user "License: Apache-2.0" (at -0.939 -5.799 90) (layer "B.Fab") hide
        (effects (font (size 0.7 0.7) (thickness 0.15)) (justify left bottom mirror))
    )
    (fp_rect (start -0.925 0.47) (end 0.925 -0.47)
      (stroke (width 0.05) (type default)) (fill none) (layer "B.CrtYd"))
    (fp_line (start -0.494 -0.248) (end -0.494 0.25)
      (stroke (width 0.15) (type solid)) (layer "B.Fab"))
    (fp_line (start -0.494 0.25) (end 0.504 0.25)
      (stroke (width 0.15) (type solid)) (layer "B.Fab"))
    (fp_line (start 0.504 -0.248) (end -0.494 -0.248)
      (stroke (width 0.15) (type solid)) (layer "B.Fab"))
    (fp_line (start 0.504 0.25) (end 0.504 -0.248)
      (stroke (width 0.15) (type solid)) (layer "B.Fab"))
    (pad "1" smd roundrect (at -0.48 0 270) (size 0.59 0.64) (layers "B.Cu" "B.Paste" "B.Mask") (roundrect_rratio 0.25)
      (net 1 "GND") (pintype "passive"))
    (pad "2" smd roundrect (at 0.48 0 270) (size 0.59 0.64) (layers "B.Cu" "B.Paste" "B.Mask") (roundrect_rratio 0.25)
      (net 304 "/FPGA power supply/VCCAUX") (pintype "passive"))
  )
	(footprint "antmicro-footprints:C_0402_1005Metric" (layer "B.Cu")
    (at 100.5 124.1 90)
    (descr "Capacitor SMD 0402")
    (tags "capacitor SMD 0402")
    (property "Author" "Antmicro")
    (property "Dielectric" "")
    (property "License" "Apache-2.0")
    (property "MPN" "C1005X5R1E474M050BB")
    (property "Manufacturer" "TDK")
    (property "Public" "False")
    (property "Sheetfile" "fpga-power-supply.kicad_sch")
    (property "Sheetname" "FPGA power supply")
    (property "Val" "470n")
    (property "Voltage" "")
    (property "ki_description" "SMD Multilayer Ceramic Capacitor, 0.47 µF, 25 V, 0402 [1005 Metric], ± 20%, X5R, C")
    (property "ki_keywords" "0402, SMT, CAPACITOR, PASSIVE, CERAMIC, MLCC")
    (attr smd)
    (fp_text reference "C181" (at -21.975 0.33 90) (layer "B.SilkS")
        (effects (font (size 0.7 0.7) (thickness 0.127)) (justify mirror))
    )
    (fp_text value "C_470n_0402" (at 0 -1.17 90) (layer "B.Fab")
        (effects (font (size 1 1) (thickness 0.15)) (justify mirror))
    )
    (fp_text user "License: Apache-2.0" (at -0.939 -5.799 270) (layer "B.Fab") hide
        (effects (font (size 0.7 0.7) (thickness 0.15)) (justify left bottom mirror))
    )
    (fp_text user "${REFERENCE}" (at 0 0 90) (layer "B.Fab")
        (effects (font (size 0.25 0.25) (thickness 0.04)) (justify mirror))
    )
    (fp_text user "Author: Antmicro" (at -0.939 -3.399 270) (layer "B.Fab") hide
        (effects (font (size 0.7 0.7) (thickness 0.15)) (justify left bottom mirror))
    )
    (fp_rect (start -0.925 0.47) (end 0.925 -0.47)
      (stroke (width 0.05) (type default)) (fill none) (layer "B.CrtYd"))
    (fp_line (start -0.494 -0.248) (end -0.494 0.25)
      (stroke (width 0.15) (type solid)) (layer "B.Fab"))
    (fp_line (start -0.494 0.25) (end 0.504 0.25)
      (stroke (width 0.15) (type solid)) (layer "B.Fab"))
    (fp_line (start 0.504 -0.248) (end -0.494 -0.248)
      (stroke (width 0.15) (type solid)) (layer "B.Fab"))
    (fp_line (start 0.504 0.25) (end 0.504 -0.248)
      (stroke (width 0.15) (type solid)) (layer "B.Fab"))
    (pad "1" smd roundrect (at -0.48 0 90) (size 0.59 0.64) (layers "B.Cu" "B.Paste" "B.Mask") (roundrect_rratio 0.25)
      (net 211 "VCC1V2") (pintype "passive"))
    (pad "2" smd roundrect (at 0.48 0 90) (size 0.59 0.64) (layers "B.Cu" "B.Paste" "B.Mask") (roundrect_rratio 0.25)
      (net 1 "GND") (pintype "passive"))
  )
	(footprint "antmicro-footprints:C_0402_1005Metric" (layer "B.Cu")
    (at 97.6 123.35)
    (descr "Capacitor SMD 0402")
    (tags "capacitor SMD 0402")
    (property "Author" "Antmicro")
    (property "Dielectric" "")
    (property "License" "Apache-2.0")
    (property "MPN" "C1005X5R1E474M050BB")
    (property "Manufacturer" "TDK")
    (property "Public" "False")
    (property "Sheetfile" "fpga-power-supply.kicad_sch")
    (property "Sheetname" "FPGA power supply")
    (property "Val" "470n")
    (property "Voltage" "")
    (property "ki_description" "SMD Multilayer Ceramic Capacitor, 0.47 µF, 25 V, 0402 [1005 Metric], ± 20%, X5R, C")
    (property "ki_keywords" "0402, SMT, CAPACITOR, PASSIVE, CERAMIC, MLCC")
    (attr smd)
    (fp_text reference "C182" (at -2.45 0.525) (layer "B.SilkS")
        (effects (font (size 0.7 0.7) (thickness 0.127)) (justify mirror))
    )
    (fp_text value "C_470n_0402" (at 0 -1.17) (layer "B.Fab")
        (effects (font (size 1 1) (thickness 0.15)) (justify mirror))
    )
    (fp_text user "License: Apache-2.0" (at -0.939 -5.799 180) (layer "B.Fab") hide
        (effects (font (size 0.7 0.7) (thickness 0.15)) (justify left bottom mirror))
    )
    (fp_text user "Author: Antmicro" (at -0.939 -3.399 180) (layer "B.Fab") hide
        (effects (font (size 0.7 0.7) (thickness 0.15)) (justify left bottom mirror))
    )
    (fp_text user "${REFERENCE}" (at 0 0) (layer "B.Fab")
        (effects (font (size 0.25 0.25) (thickness 0.04)) (justify mirror))
    )
    (fp_rect (start -0.925 0.47) (end 0.925 -0.47)
      (stroke (width 0.05) (type default)) (fill none) (layer "B.CrtYd"))
    (fp_line (start -0.494 -0.248) (end -0.494 0.25)
      (stroke (width 0.15) (type solid)) (layer "B.Fab"))
    (fp_line (start -0.494 0.25) (end 0.504 0.25)
      (stroke (width 0.15) (type solid)) (layer "B.Fab"))
    (fp_line (start 0.504 -0.248) (end -0.494 -0.248)
      (stroke (width 0.15) (type solid)) (layer "B.Fab"))
    (fp_line (start 0.504 0.25) (end 0.504 -0.248)
      (stroke (width 0.15) (type solid)) (layer "B.Fab"))
    (pad "1" smd roundrect (at -0.48 0) (size 0.59 0.64) (layers "B.Cu" "B.Paste" "B.Mask") (roundrect_rratio 0.25)
      (net 1 "GND") (pintype "passive"))
    (pad "2" smd roundrect (at 0.48 0) (size 0.59 0.64) (layers "B.Cu" "B.Paste" "B.Mask") (roundrect_rratio 0.25)
      (net 304 "/FPGA power supply/VCCAUX") (pintype "passive"))
  )
	(footprint "antmicro-footprints:C_0402_1005Metric" (layer "B.Cu")
    (at 103.6 124.065 90)
    (descr "Capacitor SMD 0402")
    (tags "capacitor SMD 0402")
    (property "Author" "Antmicro")
    (property "Dielectric" "")
    (property "License" "Apache-2.0")
    (property "MPN" "C1005X5R1E474M050BB")
    (property "Manufacturer" "TDK")
    (property "Public" "False")
    (property "Sheetfile" "fpga-power-supply.kicad_sch")
    (property "Sheetname" "FPGA power supply")
    (property "Val" "470n")
    (property "Voltage" "")
    (property "ki_description" "SMD Multilayer Ceramic Capacitor, 0.47 µF, 25 V, 0402 [1005 Metric], ± 20%, X5R, C")
    (property "ki_keywords" "0402, SMT, CAPACITOR, PASSIVE, CERAMIC, MLCC")
    (attr smd)
    (fp_text reference "C183" (at -21.97 0.89 90) (layer "B.SilkS")
        (effects (font (size 0.7 0.7) (thickness 0.127)) (justify mirror))
    )
    (fp_text value "C_470n_0402" (at 0 -1.17 90) (layer "B.Fab")
        (effects (font (size 1 1) (thickness 0.15)) (justify mirror))
    )
    (fp_text user "License: Apache-2.0" (at -0.939 -5.799 270) (layer "B.Fab") hide
        (effects (font (size 0.7 0.7) (thickness 0.15)) (justify left bottom mirror))
    )
    (fp_text user "Author: Antmicro" (at -0.939 -3.399 270) (layer "B.Fab") hide
        (effects (font (size 0.7 0.7) (thickness 0.15)) (justify left bottom mirror))
    )
    (fp_text user "${REFERENCE}" (at 0 0 90) (layer "B.Fab")
        (effects (font (size 0.25 0.25) (thickness 0.04)) (justify mirror))
    )
    (fp_rect (start -0.925 0.47) (end 0.925 -0.47)
      (stroke (width 0.05) (type default)) (fill none) (layer "B.CrtYd"))
    (fp_line (start -0.494 -0.248) (end -0.494 0.25)
      (stroke (width 0.15) (type solid)) (layer "B.Fab"))
    (fp_line (start -0.494 0.25) (end 0.504 0.25)
      (stroke (width 0.15) (type solid)) (layer "B.Fab"))
    (fp_line (start 0.504 -0.248) (end -0.494 -0.248)
      (stroke (width 0.15) (type solid)) (layer "B.Fab"))
    (fp_line (start 0.504 0.25) (end 0.504 -0.248)
      (stroke (width 0.15) (type solid)) (layer "B.Fab"))
    (pad "1" smd roundrect (at -0.48 0 90) (size 0.59 0.64) (layers "B.Cu" "B.Paste" "B.Mask") (roundrect_rratio 0.25)
      (net 211 "VCC1V2") (pintype "passive"))
    (pad "2" smd roundrect (at 0.48 0 90) (size 0.59 0.64) (layers "B.Cu" "B.Paste" "B.Mask") (roundrect_rratio 0.25)
      (net 1 "GND") (pintype "passive"))
  )
)
